(kicad_pcb
	(version 20260206)
	(generator "pcbnew")
	(generator_version "10.0")
	(general
		(thickness 1.6)
		(legacy_teardrops no)
	)
	(paper "A4")
	(title_block
		(title "04192023_DAF0TMB3IC0_F0TG_MB_C_brd_V02_OCP.brd")
		(comment 1 "Grand Teton / footprints 3773-3779 of 8354")
	)
	(layers
		(0 "F.Cu" signal "TOP")
		(4 "In1.Cu" signal "GND")
		(6 "In2.Cu" signal "IN1")
		(8 "In3.Cu" signal "GND1")
		(10 "In4.Cu" signal "IN2")
		(12 "In5.Cu" signal "GND2")
		(14 "In6.Cu" signal "IN3")
		(16 "In7.Cu" signal "GND3")
		(18 "In8.Cu" signal "VCC")
		(20 "In9.Cu" signal "VCC1")
		(22 "In10.Cu" signal "GND4")
		(24 "In11.Cu" signal "IN4")
		(26 "In12.Cu" signal "GND5")
		(28 "In13.Cu" signal "IN5")
		(30 "In14.Cu" signal "GND6")
		(32 "In15.Cu" signal "IN6")
		(34 "In16.Cu" signal "GND7")
		(2 "B.Cu" signal "BOTTOM")
		(9 "F.Adhes" user "F.Adhesive")
		(11 "B.Adhes" user "B.Adhesive")
		(13 "F.Paste" user "Package Geometry/Pastemask Top")
		(15 "B.Paste" user "Package Geometry/Pastemask Bottom")
		(5 "F.SilkS" user "Ref Des/Silkscreen Top")
		(7 "B.SilkS" user "Ref Des/Silkscreen Bottom")
		(1 "F.Mask" user "Board Geometry/Soldermask Top")
		(3 "B.Mask" user "Board Geometry/Soldermask Bottom")
		(17 "Dwgs.User" user "User.Drawings")
		(19 "Cmts.User" user "User.Comments")
		(21 "Eco1.User" user "User.Eco1")
		(23 "Eco2.User" user "User.Eco2")
		(25 "Edge.Cuts" user "Board Geometry/Outline")
		(27 "Margin" user)
		(31 "F.CrtYd" user "Package Geometry/Place Bound Top")
		(29 "B.CrtYd" user "Package Geometry/Place Bound Bottom")
		(35 "F.Fab" user "Ref Des/Assembly Top")
		(33 "B.Fab" user "Ref Des/Assembly Bottom")
	)
	(footprint ""
		(layer "F.Cu")
		(at 77.654912 -180.630068)
		(property "Reference" "PC318"
			(at 0 0 0)
			(layer "F.SilkS")
			(hide yes)
			(effects
				(font
					(size 1.27 1.27)
				)
			)
		)
		(property "Value" ""
			(at 0 0 0)
			(layer "F.Fab")
			(effects
				(font
					(size 1.27 1.27)
				)
			)
		)
		(duplicate_pad_numbers_are_jumpers no)
		(fp_line
			(start -0.7874 -0.4064)
			(end 0.7874 -0.4064)
			(stroke
				(width 0.1524)
				(type default)
			)
			(layer "F.SilkS")
		)
		(fp_line
			(start -0.7874 0.4064)
			(end -0.7874 -0.4064)
			(stroke
				(width 0.1524)
				(type default)
			)
			(layer "F.SilkS")
		)
		(fp_line
			(start 0.7874 -0.4064)
			(end 0.7874 0.4064)
			(stroke
				(width 0.1524)
				(type default)
			)
			(layer "F.SilkS")
		)
		(fp_line
			(start 0.7874 0.4064)
			(end -0.7874 0.4064)
			(stroke
				(width 0.1524)
				(type default)
			)
			(layer "F.SilkS")
		)
		(fp_line
			(start -0.67945 -0.305054)
			(end -0.12065 -0.305054)
			(stroke
				(width 0.1)
				(type default)
			)
			(layer "F.Fab")
		)
		(fp_line
			(start -0.67945 0.3048)
			(end -0.67945 -0.305054)
			(stroke
				(width 0.1)
				(type default)
			)
			(layer "F.Fab")
		)
		(fp_line
			(start -0.12065 -0.305054)
			(end -0.12065 -0.2794)
			(stroke
				(width 0.1)
				(type default)
			)
			(layer "F.Fab")
		)
		(fp_line
			(start -0.12065 -0.2794)
			(end 0.12065 -0.2794)
			(stroke
				(width 0.1)
				(type default)
			)
			(layer "F.Fab")
		)
		(fp_line
			(start -0.12065 0.2794)
			(end -0.12065 0.3048)
			(stroke
				(width 0.1)
				(type default)
			)
			(layer "F.Fab")
		)
		(fp_line
			(start -0.12065 0.3048)
			(end -0.67945 0.3048)
			(stroke
				(width 0.1)
				(type default)
			)
			(layer "F.Fab")
		)
		(fp_line
			(start 0.120396 0.2794)
			(end -0.12065 0.2794)
			(stroke
				(width 0.1)
				(type default)
			)
			(layer "F.Fab")
		)
		(fp_line
			(start 0.120396 0.3048)
			(end 0.120396 0.2794)
			(stroke
				(width 0.1)
				(type default)
			)
			(layer "F.Fab")
		)
		(fp_line
			(start 0.12065 -0.3048)
			(end 0.67945 -0.3048)
			(stroke
				(width 0.1)
				(type default)
			)
			(layer "F.Fab")
		)
		(fp_line
			(start 0.12065 -0.2794)
			(end 0.12065 -0.3048)
			(stroke
				(width 0.1)
				(type default)
			)
			(layer "F.Fab")
		)
		(fp_line
			(start 0.67945 -0.3048)
			(end 0.67945 0.3048)
			(stroke
				(width 0.1)
				(type default)
			)
			(layer "F.Fab")
		)
		(fp_line
			(start 0.67945 0.3048)
			(end 0.120396 0.3048)
			(stroke
				(width 0.1)
				(type default)
			)
			(layer "F.Fab")
		)
		(pad "1" smd circle
			(at -0.40005 0)
			(size 0 0)
			(layers "F.Cu" "F.Mask" "F.Paste")
			(net "SW_PVDDCR_CPU0_P1_SW5")
		)
		(pad "2" smd circle
			(at 0.40005 0)
			(size 0 0)
			(layers "F.Cu" "F.Mask" "F.Paste")
			(net "SW_PVDDCR_CPU0_P1_SW5_RC")
		)
	)
	(footprint ""
		(layer "F.Cu")
		(at 213.8426 -138.124438 -90)
		(property "Reference" "R2531"
			(at 0 0 270)
			(layer "F.SilkS")
			(hide yes)
			(effects
				(font
					(size 1.27 1.27)
				)
			)
		)
		(property "Value" ""
			(at 0 0 270)
			(layer "F.Fab")
			(effects
				(font
					(size 1.27 1.27)
				)
			)
		)
		(duplicate_pad_numbers_are_jumpers no)
		(fp_line
			(start -0.7874 0.4064)
			(end -0.7874 -0.4064)
			(stroke
				(width 0.1524)
				(type default)
			)
			(layer "F.SilkS")
		)
		(fp_line
			(start 0.7874 0.4064)
			(end -0.7874 0.4064)
			(stroke
				(width 0.1524)
				(type default)
			)
			(layer "F.SilkS")
		)
		(fp_line
			(start -0.7874 -0.4064)
			(end 0.7874 -0.4064)
			(stroke
				(width 0.1524)
				(type default)
			)
			(layer "F.SilkS")
		)
		(fp_line
			(start 0.7874 -0.4064)
			(end 0.7874 0.4064)
			(stroke
				(width 0.1524)
				(type default)
			)
			(layer "F.SilkS")
		)
		(fp_line
			(start -0.67945 0.3048)
			(end -0.67945 -0.305054)
			(stroke
				(width 0.1)
				(type default)
			)
			(layer "F.Fab")
		)
		(fp_line
			(start -0.12065 0.3048)
			(end -0.67945 0.3048)
			(stroke
				(width 0.1)
				(type default)
			)
			(layer "F.Fab")
		)
		(fp_line
			(start 0.120396 0.3048)
			(end 0.120396 0.2794)
			(stroke
				(width 0.1)
				(type default)
			)
			(layer "F.Fab")
		)
		(fp_line
			(start 0.67945 0.3048)
			(end 0.120396 0.3048)
			(stroke
				(width 0.1)
				(type default)
			)
			(layer "F.Fab")
		)
		(fp_line
			(start -0.12065 0.2794)
			(end -0.12065 0.3048)
			(stroke
				(width 0.1)
				(type default)
			)
			(layer "F.Fab")
		)
		(fp_line
			(start 0.120396 0.2794)
			(end -0.12065 0.2794)
			(stroke
				(width 0.1)
				(type default)
			)
			(layer "F.Fab")
		)
		(fp_line
			(start -0.12065 -0.2794)
			(end 0.12065 -0.2794)
			(stroke
				(width 0.1)
				(type default)
			)
			(layer "F.Fab")
		)
		(fp_line
			(start 0.12065 -0.2794)
			(end 0.12065 -0.3048)
			(stroke
				(width 0.1)
				(type default)
			)
			(layer "F.Fab")
		)
		(fp_line
			(start 0.12065 -0.3048)
			(end 0.67945 -0.3048)
			(stroke
				(width 0.1)
				(type default)
			)
			(layer "F.Fab")
		)
		(fp_line
			(start 0.67945 -0.3048)
			(end 0.67945 0.3048)
			(stroke
				(width 0.1)
				(type default)
			)
			(layer "F.Fab")
		)
		(fp_line
			(start -0.67945 -0.305054)
			(end -0.12065 -0.305054)
			(stroke
				(width 0.1)
				(type default)
			)
			(layer "F.Fab")
		)
		(fp_line
			(start -0.12065 -0.305054)
			(end -0.12065 -0.2794)
			(stroke
				(width 0.1)
				(type default)
			)
			(layer "F.Fab")
		)
		(pad "1" smd circle
			(at -0.40005 0 270)
			(size 0 0)
			(layers "F.Cu" "F.Mask" "F.Paste")
			(net "MB0_P12V_STBY_PWRGD")
		)
		(pad "2" smd circle
			(at 0.40005 0 270)
			(size 0 0)
			(layers "F.Cu" "F.Mask" "F.Paste")
			(net "FM_P12V_HSC_EN_R")
		)
	)
	(footprint ""
		(layer "F.Cu")
		(at 101.958902 -370.57203 -90)
		(property "Reference" "C714"
			(at 0 0 270)
			(layer "F.SilkS")
			(hide yes)
			(effects
				(font
					(size 1.27 1.27)
				)
			)
		)
		(property "Value" ""
			(at 0 0 270)
			(layer "F.Fab")
			(effects
				(font
					(size 1.27 1.27)
				)
			)
		)
		(duplicate_pad_numbers_are_jumpers no)
		(fp_line
			(start -0.299974 0.150114)
			(end -0.299974 -0.150114)
			(stroke
				(width 0.1)
				(type default)
			)
			(layer "F.Fab")
		)
		(fp_line
			(start 0.299974 0.150114)
			(end -0.299974 0.150114)
			(stroke
				(width 0.1)
				(type default)
			)
			(layer "F.Fab")
		)
		(fp_line
			(start -0.299974 -0.150114)
			(end 0.299974 -0.150114)
			(stroke
				(width 0.1)
				(type default)
			)
			(layer "F.Fab")
		)
		(fp_line
			(start 0.299974 -0.150114)
			(end 0.299974 0.150114)
			(stroke
				(width 0.1)
				(type default)
			)
			(layer "F.Fab")
		)
		(pad "1" smd rect
			(at -0.2667 0 270)
			(size 0.3048 0.381)
			(layers "F.Cu" "F.Mask" "F.Paste")
			(net "P5E_CPU1_P1_TX_C_DN<13>")
		)
		(pad "2" smd rect
			(at 0.2667 0 270)
			(size 0.3048 0.381)
			(layers "F.Cu" "F.Mask" "F.Paste")
			(net "P5E_CPU1_P1_TX_DN<13>")
		)
	)
	(footprint ""
		(layer "F.Cu")
		(at 148.642324 -115.377468)
		(property "Reference" "R8118"
			(at 0 0 0)
			(layer "F.SilkS")
			(hide yes)
			(effects
				(font
					(size 1.27 1.27)
				)
			)
		)
		(property "Value" ""
			(at 0 0 0)
			(layer "F.Fab")
			(effects
				(font
					(size 1.27 1.27)
				)
			)
		)
		(duplicate_pad_numbers_are_jumpers no)
		(fp_line
			(start -0.7874 -0.4064)
			(end 0.7874 -0.4064)
			(stroke
				(width 0.1524)
				(type default)
			)
			(layer "F.SilkS")
		)
		(fp_line
			(start -0.7874 0.4064)
			(end -0.7874 -0.4064)
			(stroke
				(width 0.1524)
				(type default)
			)
			(layer "F.SilkS")
		)
		(fp_line
			(start 0.7874 -0.4064)
			(end 0.7874 0.4064)
			(stroke
				(width 0.1524)
				(type default)
			)
			(layer "F.SilkS")
		)
		(fp_line
			(start 0.7874 0.4064)
			(end -0.7874 0.4064)
			(stroke
				(width 0.1524)
				(type default)
			)
			(layer "F.SilkS")
		)
		(fp_line
			(start -0.67945 -0.305054)
			(end -0.12065 -0.305054)
			(stroke
				(width 0.1)
				(type default)
			)
			(layer "F.Fab")
		)
		(fp_line
			(start -0.67945 0.3048)
			(end -0.67945 -0.305054)
			(stroke
				(width 0.1)
				(type default)
			)
			(layer "F.Fab")
		)
		(fp_line
			(start -0.12065 -0.305054)
			(end -0.12065 -0.2794)
			(stroke
				(width 0.1)
				(type default)
			)
			(layer "F.Fab")
		)
		(fp_line
			(start -0.12065 -0.2794)
			(end 0.12065 -0.2794)
			(stroke
				(width 0.1)
				(type default)
			)
			(layer "F.Fab")
		)
		(fp_line
			(start -0.12065 0.2794)
			(end -0.12065 0.3048)
			(stroke
				(width 0.1)
				(type default)
			)
			(layer "F.Fab")
		)
		(fp_line
			(start -0.12065 0.3048)
			(end -0.67945 0.3048)
			(stroke
				(width 0.1)
				(type default)
			)
			(layer "F.Fab")
		)
		(fp_line
			(start 0.120396 0.2794)
			(end -0.12065 0.2794)
			(stroke
				(width 0.1)
				(type default)
			)
			(layer "F.Fab")
		)
		(fp_line
			(start 0.120396 0.3048)
			(end 0.120396 0.2794)
			(stroke
				(width 0.1)
				(type default)
			)
			(layer "F.Fab")
		)
		(fp_line
			(start 0.12065 -0.3048)
			(end 0.67945 -0.3048)
			(stroke
				(width 0.1)
				(type default)
			)
			(layer "F.Fab")
		)
		(fp_line
			(start 0.12065 -0.2794)
			(end 0.12065 -0.3048)
			(stroke
				(width 0.1)
				(type default)
			)
			(layer "F.Fab")
		)
		(fp_line
			(start 0.67945 -0.3048)
			(end 0.67945 0.3048)
			(stroke
				(width 0.1)
				(type default)
			)
			(layer "F.Fab")
		)
		(fp_line
			(start 0.67945 0.3048)
			(end 0.120396 0.3048)
			(stroke
				(width 0.1)
				(type default)
			)
			(layer "F.Fab")
		)
		(pad "1" smd circle
			(at -0.40005 0)
			(size 0 0)
			(layers "F.Cu" "F.Mask" "F.Paste")
			(net "FM_UV_ADR_TRIGGER_N_R2")
		)
		(pad "2" smd circle
			(at 0.40005 0)
			(size 0 0)
			(layers "F.Cu" "F.Mask" "F.Paste")
			(net "FM_UV_ADR_TRIGGER_N")
		)
	)
	(footprint ""
		(layer "F.Cu")
		(at 37.64026 -351.372932 90)
		(property "Reference" "PR373"
			(at 0 0 90)
			(layer "F.SilkS")
			(hide yes)
			(effects
				(font
					(size 1.27 1.27)
				)
			)
		)
		(property "Value" ""
			(at 0 0 90)
			(layer "F.Fab")
			(effects
				(font
					(size 1.27 1.27)
				)
			)
		)
		(duplicate_pad_numbers_are_jumpers no)
		(fp_line
			(start 0.7874 -0.4064)
			(end 0.7874 0.4064)
			(stroke
				(width 0.1524)
				(type default)
			)
			(layer "F.SilkS")
		)
		(fp_line
			(start -0.7874 -0.4064)
			(end 0.7874 -0.4064)
			(stroke
				(width 0.1524)
				(type default)
			)
			(layer "F.SilkS")
		)
		(fp_line
			(start 0.7874 0.4064)
			(end -0.7874 0.4064)
			(stroke
				(width 0.1524)
				(type default)
			)
			(layer "F.SilkS")
		)
		(fp_line
			(start -0.7874 0.4064)
			(end -0.7874 -0.4064)
			(stroke
				(width 0.1524)
				(type default)
			)
			(layer "F.SilkS")
		)
		(fp_line
			(start -0.12065 -0.305054)
			(end -0.12065 -0.2794)
			(stroke
				(width 0.1)
				(type default)
			)
			(layer "F.Fab")
		)
		(fp_line
			(start -0.67945 -0.305054)
			(end -0.12065 -0.305054)
			(stroke
				(width 0.1)
				(type default)
			)
			(layer "F.Fab")
		)
		(fp_line
			(start 0.67945 -0.3048)
			(end 0.67945 0.3048)
			(stroke
				(width 0.1)
				(type default)
			)
			(layer "F.Fab")
		)
		(fp_line
			(start 0.12065 -0.3048)
			(end 0.67945 -0.3048)
			(stroke
				(width 0.1)
				(type default)
			)
			(layer "F.Fab")
		)
		(fp_line
			(start 0.12065 -0.2794)
			(end 0.12065 -0.3048)
			(stroke
				(width 0.1)
				(type default)
			)
			(layer "F.Fab")
		)
		(fp_line
			(start -0.12065 -0.2794)
			(end 0.12065 -0.2794)
			(stroke
				(width 0.1)
				(type default)
			)
			(layer "F.Fab")
		)
		(fp_line
			(start 0.120396 0.2794)
			(end -0.12065 0.2794)
			(stroke
				(width 0.1)
				(type default)
			)
			(layer "F.Fab")
		)
		(fp_line
			(start -0.12065 0.2794)
			(end -0.12065 0.3048)
			(stroke
				(width 0.1)
				(type default)
			)
			(layer "F.Fab")
		)
		(fp_line
			(start 0.67945 0.3048)
			(end 0.120396 0.3048)
			(stroke
				(width 0.1)
				(type default)
			)
			(layer "F.Fab")
		)
		(fp_line
			(start 0.120396 0.3048)
			(end 0.120396 0.2794)
			(stroke
				(width 0.1)
				(type default)
			)
			(layer "F.Fab")
		)
		(fp_line
			(start -0.12065 0.3048)
			(end -0.67945 0.3048)
			(stroke
				(width 0.1)
				(type default)
			)
			(layer "F.Fab")
		)
		(fp_line
			(start -0.67945 0.3048)
			(end -0.67945 -0.305054)
			(stroke
				(width 0.1)
				(type default)
			)
			(layer "F.Fab")
		)
		(pad "1" smd circle
			(at -0.40005 0 90)
			(size 0 0)
			(layers "F.Cu" "F.Mask" "F.Paste")
			(net "SW_PVDDIO_P1_BOOT3")
		)
		(pad "2" smd circle
			(at 0.40005 0 90)
			(size 0 0)
			(layers "F.Cu" "F.Mask" "F.Paste")
			(net "SW_PVDDIO_P1_BOOT3_R")
		)
	)
	(footprint ""
		(layer "F.Cu")
		(at 177.223674 -353.958652 90)
		(property "Reference" "PR387"
			(at 0 0 90)
			(layer "F.SilkS")
			(hide yes)
			(effects
				(font
					(size 1.27 1.27)
				)
			)
		)
		(property "Value" ""
			(at 0 0 90)
			(layer "F.Fab")
			(effects
				(font
					(size 1.27 1.27)
				)
			)
		)
		(duplicate_pad_numbers_are_jumpers no)
		(fp_line
			(start 0.7874 -0.4064)
			(end 0.7874 0.4064)
			(stroke
				(width 0.1524)
				(type default)
			)
			(layer "F.SilkS")
		)
		(fp_line
			(start -0.7874 -0.4064)
			(end 0.7874 -0.4064)
			(stroke
				(width 0.1524)
				(type default)
			)
			(layer "F.SilkS")
		)
		(fp_line
			(start 0.7874 0.4064)
			(end -0.7874 0.4064)
			(stroke
				(width 0.1524)
				(type default)
			)
			(layer "F.SilkS")
		)
		(fp_line
			(start -0.7874 0.4064)
			(end -0.7874 -0.4064)
			(stroke
				(width 0.1524)
				(type default)
			)
			(layer "F.SilkS")
		)
		(fp_line
			(start -0.12065 -0.305054)
			(end -0.12065 -0.2794)
			(stroke
				(width 0.1)
				(type default)
			)
			(layer "F.Fab")
		)
		(fp_line
			(start -0.67945 -0.305054)
			(end -0.12065 -0.305054)
			(stroke
				(width 0.1)
				(type default)
			)
			(layer "F.Fab")
		)
		(fp_line
			(start 0.67945 -0.3048)
			(end 0.67945 0.3048)
			(stroke
				(width 0.1)
				(type default)
			)
			(layer "F.Fab")
		)
		(fp_line
			(start 0.12065 -0.3048)
			(end 0.67945 -0.3048)
			(stroke
				(width 0.1)
				(type default)
			)
			(layer "F.Fab")
		)
		(fp_line
			(start 0.12065 -0.2794)
			(end 0.12065 -0.3048)
			(stroke
				(width 0.1)
				(type default)
			)
			(layer "F.Fab")
		)
		(fp_line
			(start -0.12065 -0.2794)
			(end 0.12065 -0.2794)
			(stroke
				(width 0.1)
				(type default)
			)
			(layer "F.Fab")
		)
		(fp_line
			(start 0.120396 0.2794)
			(end -0.12065 0.2794)
			(stroke
				(width 0.1)
				(type default)
			)
			(layer "F.Fab")
		)
		(fp_line
			(start -0.12065 0.2794)
			(end -0.12065 0.3048)
			(stroke
				(width 0.1)
				(type default)
			)
			(layer "F.Fab")
		)
		(fp_line
			(start 0.67945 0.3048)
			(end 0.120396 0.3048)
			(stroke
				(width 0.1)
				(type default)
			)
			(layer "F.Fab")
		)
		(fp_line
			(start 0.120396 0.3048)
			(end 0.120396 0.2794)
			(stroke
				(width 0.1)
				(type default)
			)
			(layer "F.Fab")
		)
		(fp_line
			(start -0.12065 0.3048)
			(end -0.67945 0.3048)
			(stroke
				(width 0.1)
				(type default)
			)
			(layer "F.Fab")
		)
		(fp_line
			(start -0.67945 0.3048)
			(end -0.67945 -0.305054)
			(stroke
				(width 0.1)
				(type default)
			)
			(layer "F.Fab")
		)
		(pad "1" smd circle
			(at -0.40005 0 90)
			(size 0 0)
			(layers "F.Cu" "F.Mask" "F.Paste")
			(net "PVDD11_S3_P1_PVCC")
		)
		(pad "2" smd circle
			(at 0.40005 0 90)
			(size 0 0)
			(layers "F.Cu" "F.Mask" "F.Paste")
			(net "P5V_AUX")
		)
	)
	(footprint ""
		(layer "F.Cu")
		(at 75.08748 -333.258668 90)
		(property "Reference" "PR513"
			(at 0 0 90)
			(layer "F.SilkS")
			(hide yes)
			(effects
				(font
					(size 1.27 1.27)
				)
			)
		)
		(property "Value" ""
			(at 0 0 90)
			(layer "F.Fab")
			(effects
				(font
					(size 1.27 1.27)
				)
			)
		)
		(duplicate_pad_numbers_are_jumpers no)
		(fp_line
			(start 0.7874 -0.4064)
			(end 0.7874 0.4064)
			(stroke
				(width 0.1524)
				(type default)
			)
			(layer "F.SilkS")
		)
		(fp_line
			(start -0.7874 -0.4064)
			(end 0.7874 -0.4064)
			(stroke
				(width 0.1524)
				(type default)
			)
			(layer "F.SilkS")
		)
		(fp_line
			(start 0.7874 0.4064)
			(end -0.7874 0.4064)
			(stroke
				(width 0.1524)
				(type default)
			)
			(layer "F.SilkS")
		)
		(fp_line
			(start -0.7874 0.4064)
			(end -0.7874 -0.4064)
			(stroke
				(width 0.1524)
				(type default)
			)
			(layer "F.SilkS")
		)
		(fp_line
			(start -0.12065 -0.305054)
			(end -0.12065 -0.2794)
			(stroke
				(width 0.1)
				(type default)
			)
			(layer "F.Fab")
		)
		(fp_line
			(start -0.67945 -0.305054)
			(end -0.12065 -0.305054)
			(stroke
				(width 0.1)
				(type default)
			)
			(layer "F.Fab")
		)
		(fp_line
			(start 0.67945 -0.3048)
			(end 0.67945 0.3048)
			(stroke
				(width 0.1)
				(type default)
			)
			(layer "F.Fab")
		)
		(fp_line
			(start 0.12065 -0.3048)
			(end 0.67945 -0.3048)
			(stroke
				(width 0.1)
				(type default)
			)
			(layer "F.Fab")
		)
		(fp_line
			(start 0.12065 -0.2794)
			(end 0.12065 -0.3048)
			(stroke
				(width 0.1)
				(type default)
			)
			(layer "F.Fab")
		)
		(fp_line
			(start -0.12065 -0.2794)
			(end 0.12065 -0.2794)
			(stroke
				(width 0.1)
				(type default)
			)
			(layer "F.Fab")
		)
		(fp_line
			(start 0.120396 0.2794)
			(end -0.12065 0.2794)
			(stroke
				(width 0.1)
				(type default)
			)
			(layer "F.Fab")
		)
		(fp_line
			(start -0.12065 0.2794)
			(end -0.12065 0.3048)
			(stroke
				(width 0.1)
				(type default)
			)
			(layer "F.Fab")
		)
		(fp_line
			(start 0.67945 0.3048)
			(end 0.120396 0.3048)
			(stroke
				(width 0.1)
				(type default)
			)
			(layer "F.Fab")
		)
		(fp_line
			(start 0.120396 0.3048)
			(end 0.120396 0.2794)
			(stroke
				(width 0.1)
				(type default)
			)
			(layer "F.Fab")
		)
		(fp_line
			(start -0.12065 0.3048)
			(end -0.67945 0.3048)
			(stroke
				(width 0.1)
				(type default)
			)
			(layer "F.Fab")
		)
		(fp_line
			(start -0.67945 0.3048)
			(end -0.67945 -0.305054)
			(stroke
				(width 0.1)
				(type default)
			)
			(layer "F.Fab")
		)
		(pad "1" smd circle
			(at -0.40005 0 90)
			(size 0 0)
			(layers "F.Cu" "F.Mask" "F.Paste")
			(net "SW_PVDDCR_CPU1_P1_SW2_RC")
		)
		(pad "2" smd circle
			(at 0.40005 0 90)
			(size 0 0)
			(layers "F.Cu" "F.Mask" "F.Paste")
			(net "GND")
		)
	)
)
